# BASEBOARD_FAB2 (Tioga Pass) — schematic netlist excerpt (pin names and nets, part order shuffled) for the footprints in the layout excerpt that follows; sources: Cadence DE-HDL packaged netlist, KiCad conversion of Wiwynn_Tioga_Pass_MB.brd

FB3M1  FERRITE  120 FB  pkg SM  page 127 : A = P1V05_PCH_STBY ; B = P1V05_PCH_STBY_VCCA_PLL1
C5M10  CAP_A  47UF 4V 20% X5R  pkg 0603V  page 220 : A = PVDDQ_DEF ; B = GND
C25W59  CAP  4.7UF 6.3V 10% X6S  pkg 0603  page 149 : A = VCC_PA_3V3 ; B = GND

(kicad_pcb
	(version 20260206)
	(generator "pcbnew")
	(generator_version "10.0")
	(general
		(thickness 1.6)
		(legacy_teardrops no)
	)
	(paper "A4")
	(title_block
		(title "Wiwynn_Tioga_Pass_MB.brd")
		(comment 1 "Tioga Pass / footprints 2355-2357 of 4770")
	)
	(layers
		(0 "F.Cu" signal "TOP")
		(4 "In1.Cu" signal "L2GND")
		(6 "In2.Cu" signal "L3")
		(8 "In3.Cu" signal "L4GND")
		(10 "In4.Cu" signal "L5")
		(12 "In5.Cu" signal "L6GND")
		(14 "In6.Cu" signal "L7VCC")
		(16 "In7.Cu" signal "L8VCC")
		(18 "In8.Cu" signal "L9GND")
		(20 "In9.Cu" signal "L10")
		(22 "In10.Cu" signal "L11GND")
		(24 "In11.Cu" signal "L12")
		(26 "In12.Cu" signal "L13GND")
		(2 "B.Cu" signal "BOTTOM")
		(9 "F.Adhes" user "F.Adhesive")
		(11 "B.Adhes" user "B.Adhesive")
		(13 "F.Paste" user "Package Geometry/Pastemask Top")
		(15 "B.Paste" user "Package Geometry/Pastemask Bottom")
		(5 "F.SilkS" user "Ref Des/Silkscreen Top")
		(7 "B.SilkS" user "Ref Des/Silkscreen Bottom")
		(1 "F.Mask" user "Board Geometry/Soldermask Top")
		(3 "B.Mask" user "Board Geometry/Soldermask Bottom")
		(17 "Dwgs.User" user "User.Drawings")
		(19 "Cmts.User" user "User.Comments")
		(21 "Eco1.User" user "User.Eco1")
		(23 "Eco2.User" user "User.Eco2")
		(25 "Edge.Cuts" user "Board Geometry/Outline")
		(27 "Margin" user)
		(31 "F.CrtYd" user "Package Geometry/Place Bound Top")
		(29 "B.CrtYd" user "Package Geometry/Place Bound Bottom")
		(35 "F.Fab" user "Ref Des/Assembly Top")
		(33 "B.Fab" user "Ref Des/Assembly Bottom")
	)
	(footprint ""
		(layer "B.Cu")
		(at 377.8758 -135.1788 -90)
		(property "Reference" "FB3M1"
			(at 0 0 90)
			(layer "B.SilkS")
			(hide yes)
			(effects
				(font
					(size 1.27 1.27)
				)
				(justify mirror)
			)
		)
		(property "Value" ""
			(at 0 0 90)
			(layer "B.Fab")
			(effects
				(font
					(size 1.27 1.27)
				)
				(justify mirror)
			)
		)
		(duplicate_pad_numbers_are_jumpers no)
		(fp_poly
			(pts
				(xy 0.15113 -0.47498) (xy -1.59893 -0.47498) (xy -1.59893 0.47498) (xy 0.15113 0.47498)
			)
			(stroke
				(width 0)
				(type default)
			)
			(fill no)
			(layer "B.CrtYd")
		)
		(fp_line
			(start -1.59893 0.47498)
			(end 0.15113 0.47498)
			(stroke
				(width 0.1)
				(type default)
			)
			(layer "B.Fab")
		)
		(fp_line
			(start 0.15113 0.47498)
			(end 0.15113 -0.47498)
			(stroke
				(width 0.1)
				(type default)
			)
			(layer "B.Fab")
		)
		(fp_line
			(start -1.59893 -0.47498)
			(end -1.59893 0.47498)
			(stroke
				(width 0.1)
				(type default)
			)
			(layer "B.Fab")
		)
		(fp_line
			(start 0.15113 -0.47498)
			(end -1.59893 -0.47498)
			(stroke
				(width 0.1)
				(type default)
			)
			(layer "B.Fab")
		)
		(pad "1" smd rect
			(at 0 0 90)
			(size 0.9398 0.9398)
			(layers "B.Cu" "B.Mask" "B.Paste")
			(net "P1V05_PCH_STBY")
		)
		(pad "2" smd rect
			(at -1.4478 0 90)
			(size 0.9398 0.9398)
			(layers "B.Cu" "B.Mask" "B.Paste")
			(net "P1V05_PCH_STBY_VCCA_PLL1")
		)
		(zone
			(layer "B.Cu")
			(hatch none 0.5)
			(connect_pads
				(clearance 0)
			)
			(min_thickness 0.25)
			(keepout
				(tracks not_allowed)
				(vias allowed)
				(pads allowed)
				(copperpour not_allowed)
				(footprints allowed)
			)
			(placement
				(enabled no)
				(sheetname "")
			)
			(fill
				(thermal_gap 0.5)
				(thermal_bridge_width 0.5)
				(island_removal_mode 0)
			)
			(polygon
				(pts
					(xy 377.4059 -135.6487) (xy 378.3457 -135.6487) (xy 378.3457 -136.1567) (xy 377.4059 -136.1567)
				)
			)
		)
		(zone
			(layer "B.Cu")
			(hatch none 0.5)
			(connect_pads
				(clearance 0)
			)
			(min_thickness 0.25)
			(keepout
				(tracks allowed)
				(vias not_allowed)
				(pads allowed)
				(copperpour not_allowed)
				(footprints allowed)
			)
			(placement
				(enabled no)
				(sheetname "")
			)
			(fill
				(thermal_gap 0.5)
				(thermal_bridge_width 0.5)
				(island_removal_mode 0)
			)
			(polygon
				(pts
					(xy 377.4059 -135.6487) (xy 378.3457 -135.6487) (xy 378.3457 -136.1567) (xy 377.4059 -136.1567)
				)
			)
		)
	)
	(footprint ""
		(layer "B.Cu")
		(at 425.203874 -40.931846 180)
		(property "Reference" "C25W59"
			(at -0.97536 0.76708 270)
			(unlocked yes)
			(layer "B.SilkS")
			(effects
				(font
					(size 0.4064 0.254)
					(thickness 0.1524)
				)
				(justify mirror)
			)
		)
		(property "Value" ""
			(at 0 0 0)
			(layer "B.Fab")
			(effects
				(font
					(size 1.27 1.27)
				)
				(justify mirror)
			)
		)
		(duplicate_pad_numbers_are_jumpers no)
		(fp_poly
			(pts
				(xy 0.4953 -0.2032) (xy -0.4953 -0.2032) (xy -0.4953 1.6002) (xy 0.4953 1.6002)
			)
			(stroke
				(width 0)
				(type default)
			)
			(fill no)
			(layer "B.CrtYd")
		)
		(fp_line
			(start 0.4953 1.6002)
			(end 0.4953 -0.2032)
			(stroke
				(width 0.1)
				(type default)
			)
			(layer "B.Fab")
		)
		(fp_line
			(start 0.4953 -0.2032)
			(end -0.4953 -0.2032)
			(stroke
				(width 0.1)
				(type default)
			)
			(layer "B.Fab")
		)
		(fp_line
			(start -0.4953 1.6002)
			(end 0.4953 1.6002)
			(stroke
				(width 0.1)
				(type default)
			)
			(layer "B.Fab")
		)
		(fp_line
			(start -0.4953 -0.2032)
			(end -0.4953 1.6002)
			(stroke
				(width 0.1)
				(type default)
			)
			(layer "B.Fab")
		)
		(pad "1" smd rect
			(at 0 0)
			(size 0.762 0.889)
			(layers "B.Cu" "B.Mask" "B.Paste")
			(net "VCC_PA_3V3")
		)
		(pad "2" smd rect
			(at 0 1.397)
			(size 0.762 0.889)
			(layers "B.Cu" "B.Mask" "B.Paste")
			(net "GND")
		)
		(zone
			(layer "B.Cu")
			(hatch none 0.5)
			(connect_pads
				(clearance 0)
			)
			(min_thickness 0.25)
			(keepout
				(tracks not_allowed)
				(vias allowed)
				(pads allowed)
				(copperpour not_allowed)
				(footprints allowed)
			)
			(placement
				(enabled no)
				(sheetname "")
			)
			(fill
				(thermal_gap 0.5)
				(thermal_bridge_width 0.5)
				(island_removal_mode 0)
			)
			(polygon
				(pts
					(xy 424.822874 -41.376346) (xy 425.584874 -41.376346) (xy 425.584874 -41.884346) (xy 424.822874 -41.884346)
				)
			)
		)
	)
	(footprint ""
		(layer "B.Cu")
		(at 244.5512 -125.55601 -90)
		(property "Reference" "C5M10"
			(at 0 0 90)
			(layer "B.SilkS")
			(hide yes)
			(effects
				(font
					(size 1.27 1.27)
				)
				(justify mirror)
			)
		)
		(property "Value" ""
			(at 0 0 90)
			(layer "B.Fab")
			(effects
				(font
					(size 1.27 1.27)
				)
				(justify mirror)
			)
		)
		(duplicate_pad_numbers_are_jumpers no)
		(fp_rect
			(start 0.500126 1.598422)
			(end -0.500126 -0.201422)
			(stroke
				(width 0)
				(type default)
			)
			(fill no)
			(layer "B.CrtYd")
		)
		(fp_line
			(start -0.500126 1.598422)
			(end 0.500126 1.598422)
			(stroke
				(width 0.1)
				(type default)
			)
			(layer "B.Fab")
		)
		(fp_line
			(start 0.500126 1.598422)
			(end 0.500126 -0.201422)
			(stroke
				(width 0.1)
				(type default)
			)
			(layer "B.Fab")
		)
		(fp_line
			(start -0.500126 -0.201422)
			(end -0.500126 1.598422)
			(stroke
				(width 0.1)
				(type default)
			)
			(layer "B.Fab")
		)
		(fp_line
			(start 0.500126 -0.201422)
			(end -0.500126 -0.201422)
			(stroke
				(width 0.1)
				(type default)
			)
			(layer "B.Fab")
		)
		(pad "1" smd rect
			(at 0 0 180)
			(size 0.889 0.9906)
			(layers "B.Cu" "B.Mask" "B.Paste")
			(net "PVDDQ_DEF")
		)
		(pad "2" smd rect
			(at 0 1.397 180)
			(size 0.889 0.9906)
			(layers "B.Cu" "B.Mask" "B.Paste")
			(net "GND")
		)
		(zone
			(layer "B.Cu")
			(hatch none 0.5)
			(connect_pads
				(clearance 0)
			)
			(min_thickness 0.25)
			(keepout
				(tracks allowed)
				(vias not_allowed)
				(pads allowed)
				(copperpour not_allowed)
				(footprints allowed)
			)
			(placement
				(enabled no)
				(sheetname "")
			)
			(fill
				(thermal_gap 0.5)
				(thermal_bridge_width 0.5)
				(island_removal_mode 0)
			)
			(polygon
				(pts
					(xy 243.5987 -125.06071) (xy 244.1067 -125.06071) (xy 244.1067 -126.05131) (xy 243.5987 -126.05131)
				)
			)
		)
		(zone
			(layer "B.Cu")
			(hatch none 0.5)
			(connect_pads
				(clearance 0)
			)
			(min_thickness 0.25)
			(keepout
				(tracks not_allowed)
				(vias allowed)
				(pads allowed)
				(copperpour not_allowed)
				(footprints allowed)
			)
			(placement
				(enabled no)
				(sheetname "")
			)
			(fill
				(thermal_gap 0.5)
				(thermal_bridge_width 0.5)
				(island_removal_mode 0)
			)
			(polygon
				(pts
					(xy 243.5987 -125.06071) (xy 244.1067 -125.06071) (xy 244.1067 -126.05131) (xy 243.5987 -126.05131)
				)
			)
		)
	)
)
